(kicad_pcb
	(version 20260206)
	(generator "pcbnew")
	(generator_version "10.0")
	(general
		(thickness 1.6)
		(legacy_teardrops no)
	)
	(paper "A4")
	(title_block
		(title "04192023_DAF0TMB3IC0_F0TG_MB_C_brd_V02_OCP.brd")
		(comment 1 "Grand Teton / footprints 5897-5904 of 8354")
	)
	(layers
		(0 "F.Cu" signal "TOP")
		(4 "In1.Cu" signal "GND")
		(6 "In2.Cu" signal "IN1")
		(8 "In3.Cu" signal "GND1")
		(10 "In4.Cu" signal "IN2")
		(12 "In5.Cu" signal "GND2")
		(14 "In6.Cu" signal "IN3")
		(16 "In7.Cu" signal "GND3")
		(18 "In8.Cu" signal "VCC")
		(20 "In9.Cu" signal "VCC1")
		(22 "In10.Cu" signal "GND4")
		(24 "In11.Cu" signal "IN4")
		(26 "In12.Cu" signal "GND5")
		(28 "In13.Cu" signal "IN5")
		(30 "In14.Cu" signal "GND6")
		(32 "In15.Cu" signal "IN6")
		(34 "In16.Cu" signal "GND7")
		(2 "B.Cu" signal "BOTTOM")
		(9 "F.Adhes" user "F.Adhesive")
		(11 "B.Adhes" user "B.Adhesive")
		(13 "F.Paste" user "Package Geometry/Pastemask Top")
		(15 "B.Paste" user "Package Geometry/Pastemask Bottom")
		(5 "F.SilkS" user "Ref Des/Silkscreen Top")
		(7 "B.SilkS" user "Ref Des/Silkscreen Bottom")
		(1 "F.Mask" user "Board Geometry/Soldermask Top")
		(3 "B.Mask" user "Board Geometry/Soldermask Bottom")
		(17 "Dwgs.User" user "User.Drawings")
		(19 "Cmts.User" user "User.Comments")
		(21 "Eco1.User" user "User.Eco1")
		(23 "Eco2.User" user "User.Eco2")
		(25 "Edge.Cuts" user "Board Geometry/Outline")
		(27 "Margin" user)
		(31 "F.CrtYd" user "Package Geometry/Place Bound Top")
		(29 "B.CrtYd" user "Package Geometry/Place Bound Bottom")
		(35 "F.Fab" user "Ref Des/Assembly Top")
		(33 "B.Fab" user "Ref Des/Assembly Bottom")
	)
	(footprint ""
		(layer "B.Cu")
		(at 51.120548 -195.926964 180)
		(property "Reference" "R1696"
			(at 0 0 0)
			(layer "B.SilkS")
			(hide yes)
			(effects
				(font
					(size 1.27 1.27)
				)
				(justify mirror)
			)
		)
		(property "Value" ""
			(at 0 0 0)
			(layer "B.Fab")
			(effects
				(font
					(size 1.27 1.27)
				)
				(justify mirror)
			)
		)
		(duplicate_pad_numbers_are_jumpers no)
		(fp_line
			(start 0.7874 0.4064)
			(end 0.7874 -0.4064)
			(stroke
				(width 0.1524)
				(type default)
			)
			(layer "B.SilkS")
		)
		(fp_line
			(start 0.7874 -0.4064)
			(end -0.7874 -0.4064)
			(stroke
				(width 0.1524)
				(type default)
			)
			(layer "B.SilkS")
		)
		(fp_line
			(start -0.7874 0.4064)
			(end 0.7874 0.4064)
			(stroke
				(width 0.1524)
				(type default)
			)
			(layer "B.SilkS")
		)
		(fp_line
			(start -0.7874 -0.4064)
			(end -0.7874 0.4064)
			(stroke
				(width 0.1524)
				(type default)
			)
			(layer "B.SilkS")
		)
		(fp_line
			(start 0.67945 0.3048)
			(end 0.67945 -0.305054)
			(stroke
				(width 0.1)
				(type default)
			)
			(layer "B.Fab")
		)
		(fp_line
			(start 0.67945 -0.305054)
			(end 0.12065 -0.305054)
			(stroke
				(width 0.1)
				(type default)
			)
			(layer "B.Fab")
		)
		(fp_line
			(start 0.12065 0.3048)
			(end 0.67945 0.3048)
			(stroke
				(width 0.1)
				(type default)
			)
			(layer "B.Fab")
		)
		(fp_line
			(start 0.12065 0.2794)
			(end 0.12065 0.3048)
			(stroke
				(width 0.1)
				(type default)
			)
			(layer "B.Fab")
		)
		(fp_line
			(start 0.12065 -0.2794)
			(end -0.12065 -0.2794)
			(stroke
				(width 0.1)
				(type default)
			)
			(layer "B.Fab")
		)
		(fp_line
			(start 0.12065 -0.305054)
			(end 0.12065 -0.2794)
			(stroke
				(width 0.1)
				(type default)
			)
			(layer "B.Fab")
		)
		(fp_line
			(start -0.120396 0.3048)
			(end -0.120396 0.2794)
			(stroke
				(width 0.1)
				(type default)
			)
			(layer "B.Fab")
		)
		(fp_line
			(start -0.120396 0.2794)
			(end 0.12065 0.2794)
			(stroke
				(width 0.1)
				(type default)
			)
			(layer "B.Fab")
		)
		(fp_line
			(start -0.12065 -0.2794)
			(end -0.12065 -0.3048)
			(stroke
				(width 0.1)
				(type default)
			)
			(layer "B.Fab")
		)
		(fp_line
			(start -0.12065 -0.3048)
			(end -0.67945 -0.3048)
			(stroke
				(width 0.1)
				(type default)
			)
			(layer "B.Fab")
		)
		(fp_line
			(start -0.67945 0.3048)
			(end -0.120396 0.3048)
			(stroke
				(width 0.1)
				(type default)
			)
			(layer "B.Fab")
		)
		(fp_line
			(start -0.67945 -0.3048)
			(end -0.67945 0.3048)
			(stroke
				(width 0.1)
				(type default)
			)
			(layer "B.Fab")
		)
		(pad "1" smd circle
			(at 0.40005 0)
			(size 0 0)
			(layers "B.Cu" "B.Mask" "B.Paste")
			(net "I3C_SPD_DDRAF_CPU1_SDA")
		)
		(pad "2" smd circle
			(at -0.40005 0)
			(size 0 0)
			(layers "B.Cu" "B.Mask" "B.Paste")
			(net "I3C_SPD_DDRB_CPU1_SDA")
		)
	)
	(footprint ""
		(layer "B.Cu")
		(at 418.128958 -342.007952 -90)
		(property "Reference" "PC225_2"
			(at 0 0 90)
			(layer "B.SilkS")
			(hide yes)
			(effects
				(font
					(size 1.27 1.27)
				)
				(justify mirror)
			)
		)
		(property "Value" ""
			(at 0 0 90)
			(layer "B.Fab")
			(effects
				(font
					(size 1.27 1.27)
				)
				(justify mirror)
			)
		)
		(duplicate_pad_numbers_are_jumpers no)
		(fp_line
			(start -1.524 0.762)
			(end 1.524 0.762)
			(stroke
				(width 0.1524)
				(type default)
			)
			(layer "B.SilkS")
		)
		(fp_line
			(start 1.524 0.762)
			(end 1.524 -0.762)
			(stroke
				(width 0.1524)
				(type default)
			)
			(layer "B.SilkS")
		)
		(fp_line
			(start -1.524 -0.762)
			(end -1.524 0.762)
			(stroke
				(width 0.1524)
				(type default)
			)
			(layer "B.SilkS")
		)
		(fp_line
			(start 1.524 -0.762)
			(end -1.524 -0.762)
			(stroke
				(width 0.1524)
				(type default)
			)
			(layer "B.SilkS")
		)
		(fp_line
			(start -1.1049 0.724916)
			(end -1.1049 -0.724916)
			(stroke
				(width 0.1)
				(type default)
			)
			(layer "B.Fab")
		)
		(fp_line
			(start 1.1049 0.724916)
			(end -1.1049 0.724916)
			(stroke
				(width 0.1)
				(type default)
			)
			(layer "B.Fab")
		)
		(fp_line
			(start -1.1049 -0.724916)
			(end 1.1049 -0.724916)
			(stroke
				(width 0.1)
				(type default)
			)
			(layer "B.Fab")
		)
		(fp_line
			(start 1.1049 -0.724916)
			(end 1.1049 0.724916)
			(stroke
				(width 0.1)
				(type default)
			)
			(layer "B.Fab")
		)
		(pad "1" smd rect
			(at 0.889 0 270)
			(size 1.016 1.27)
			(layers "B.Cu" "B.Mask" "B.Paste")
			(net "PVDD11_S3_P0")
		)
		(pad "2" smd rect
			(at -0.889 0 270)
			(size 1.016 1.27)
			(layers "B.Cu" "B.Mask" "B.Paste")
			(net "GND")
		)
	)
	(footprint ""
		(layer "B.Cu")
		(at 93.11894 -390.560052 90)
		(property "Reference" "C343"
			(at 0 0 90)
			(layer "B.SilkS")
			(hide yes)
			(effects
				(font
					(size 1.27 1.27)
				)
				(justify mirror)
			)
		)
		(property "Value" ""
			(at 0 0 90)
			(layer "B.Fab")
			(effects
				(font
					(size 1.27 1.27)
				)
				(justify mirror)
			)
		)
		(duplicate_pad_numbers_are_jumpers no)
		(fp_line
			(start 0.7874 -0.4064)
			(end -0.7874 -0.4064)
			(stroke
				(width 0.1524)
				(type default)
			)
			(layer "B.SilkS")
		)
		(fp_line
			(start -0.7874 -0.4064)
			(end -0.7874 0.4064)
			(stroke
				(width 0.1524)
				(type default)
			)
			(layer "B.SilkS")
		)
		(fp_line
			(start 0.7874 0.4064)
			(end 0.7874 -0.4064)
			(stroke
				(width 0.1524)
				(type default)
			)
			(layer "B.SilkS")
		)
		(fp_line
			(start -0.7874 0.4064)
			(end 0.7874 0.4064)
			(stroke
				(width 0.1524)
				(type default)
			)
			(layer "B.SilkS")
		)
		(fp_line
			(start 0.67945 -0.305054)
			(end 0.12065 -0.305054)
			(stroke
				(width 0.1)
				(type default)
			)
			(layer "B.Fab")
		)
		(fp_line
			(start 0.12065 -0.305054)
			(end 0.12065 -0.2794)
			(stroke
				(width 0.1)
				(type default)
			)
			(layer "B.Fab")
		)
		(fp_line
			(start -0.12065 -0.3048)
			(end -0.67945 -0.3048)
			(stroke
				(width 0.1)
				(type default)
			)
			(layer "B.Fab")
		)
		(fp_line
			(start -0.67945 -0.3048)
			(end -0.67945 0.3048)
			(stroke
				(width 0.1)
				(type default)
			)
			(layer "B.Fab")
		)
		(fp_line
			(start 0.12065 -0.2794)
			(end -0.12065 -0.2794)
			(stroke
				(width 0.1)
				(type default)
			)
			(layer "B.Fab")
		)
		(fp_line
			(start -0.12065 -0.2794)
			(end -0.12065 -0.3048)
			(stroke
				(width 0.1)
				(type default)
			)
			(layer "B.Fab")
		)
		(fp_line
			(start 0.12065 0.2794)
			(end 0.12065 0.3048)
			(stroke
				(width 0.1)
				(type default)
			)
			(layer "B.Fab")
		)
		(fp_line
			(start -0.120396 0.2794)
			(end 0.12065 0.2794)
			(stroke
				(width 0.1)
				(type default)
			)
			(layer "B.Fab")
		)
		(fp_line
			(start 0.67945 0.3048)
			(end 0.67945 -0.305054)
			(stroke
				(width 0.1)
				(type default)
			)
			(layer "B.Fab")
		)
		(fp_line
			(start 0.12065 0.3048)
			(end 0.67945 0.3048)
			(stroke
				(width 0.1)
				(type default)
			)
			(layer "B.Fab")
		)
		(fp_line
			(start -0.120396 0.3048)
			(end -0.120396 0.2794)
			(stroke
				(width 0.1)
				(type default)
			)
			(layer "B.Fab")
		)
		(fp_line
			(start -0.67945 0.3048)
			(end -0.120396 0.3048)
			(stroke
				(width 0.1)
				(type default)
			)
			(layer "B.Fab")
		)
		(pad "1" smd circle
			(at 0.40005 0 270)
			(size 0 0)
			(layers "B.Cu" "B.Mask" "B.Paste")
			(net "P0V9_CPU1_RT1_2A")
		)
		(pad "2" smd circle
			(at -0.40005 0 270)
			(size 0 0)
			(layers "B.Cu" "B.Mask" "B.Paste")
			(net "GND")
		)
	)
	(footprint ""
		(layer "B.Cu")
		(at 45.336968 -244.085364 180)
		(property "Reference" "R502"
			(at 0 0 0)
			(layer "B.SilkS")
			(hide yes)
			(effects
				(font
					(size 1.27 1.27)
				)
				(justify mirror)
			)
		)
		(property "Value" ""
			(at 0 0 0)
			(layer "B.Fab")
			(effects
				(font
					(size 1.27 1.27)
				)
				(justify mirror)
			)
		)
		(duplicate_pad_numbers_are_jumpers no)
		(fp_line
			(start 0.7874 0.4064)
			(end 0.7874 -0.4064)
			(stroke
				(width 0.1524)
				(type default)
			)
			(layer "B.SilkS")
		)
		(fp_line
			(start 0.7874 -0.4064)
			(end -0.7874 -0.4064)
			(stroke
				(width 0.1524)
				(type default)
			)
			(layer "B.SilkS")
		)
		(fp_line
			(start -0.7874 0.4064)
			(end 0.7874 0.4064)
			(stroke
				(width 0.1524)
				(type default)
			)
			(layer "B.SilkS")
		)
		(fp_line
			(start -0.7874 -0.4064)
			(end -0.7874 0.4064)
			(stroke
				(width 0.1524)
				(type default)
			)
			(layer "B.SilkS")
		)
		(fp_line
			(start 0.67945 0.3048)
			(end 0.67945 -0.305054)
			(stroke
				(width 0.1)
				(type default)
			)
			(layer "B.Fab")
		)
		(fp_line
			(start 0.67945 -0.305054)
			(end 0.12065 -0.305054)
			(stroke
				(width 0.1)
				(type default)
			)
			(layer "B.Fab")
		)
		(fp_line
			(start 0.12065 0.3048)
			(end 0.67945 0.3048)
			(stroke
				(width 0.1)
				(type default)
			)
			(layer "B.Fab")
		)
		(fp_line
			(start 0.12065 0.2794)
			(end 0.12065 0.3048)
			(stroke
				(width 0.1)
				(type default)
			)
			(layer "B.Fab")
		)
		(fp_line
			(start 0.12065 -0.2794)
			(end -0.12065 -0.2794)
			(stroke
				(width 0.1)
				(type default)
			)
			(layer "B.Fab")
		)
		(fp_line
			(start 0.12065 -0.305054)
			(end 0.12065 -0.2794)
			(stroke
				(width 0.1)
				(type default)
			)
			(layer "B.Fab")
		)
		(fp_line
			(start -0.120396 0.3048)
			(end -0.120396 0.2794)
			(stroke
				(width 0.1)
				(type default)
			)
			(layer "B.Fab")
		)
		(fp_line
			(start -0.120396 0.2794)
			(end 0.12065 0.2794)
			(stroke
				(width 0.1)
				(type default)
			)
			(layer "B.Fab")
		)
		(fp_line
			(start -0.12065 -0.2794)
			(end -0.12065 -0.3048)
			(stroke
				(width 0.1)
				(type default)
			)
			(layer "B.Fab")
		)
		(fp_line
			(start -0.12065 -0.3048)
			(end -0.67945 -0.3048)
			(stroke
				(width 0.1)
				(type default)
			)
			(layer "B.Fab")
		)
		(fp_line
			(start -0.67945 0.3048)
			(end -0.120396 0.3048)
			(stroke
				(width 0.1)
				(type default)
			)
			(layer "B.Fab")
		)
		(fp_line
			(start -0.67945 -0.3048)
			(end -0.67945 0.3048)
			(stroke
				(width 0.1)
				(type default)
			)
			(layer "B.Fab")
		)
		(pad "1" smd circle
			(at 0.40005 0)
			(size 0 0)
			(layers "B.Cu" "B.Mask" "B.Paste")
			(net "M_C_CPU1_ALERT_N")
		)
		(pad "2" smd circle
			(at -0.40005 0)
			(size 0 0)
			(layers "B.Cu" "B.Mask" "B.Paste")
			(net "M_C_CPU1_ALERT_R_N")
		)
	)
	(footprint ""
		(layer "B.Cu")
		(at 418.606224 -395.148562 90)
		(property "Reference" "C788"
			(at 0 0 90)
			(layer "B.SilkS")
			(hide yes)
			(effects
				(font
					(size 1.27 1.27)
				)
				(justify mirror)
			)
		)
		(property "Value" ""
			(at 0 0 90)
			(layer "B.Fab")
			(effects
				(font
					(size 1.27 1.27)
				)
				(justify mirror)
			)
		)
		(duplicate_pad_numbers_are_jumpers no)
		(fp_line
			(start 0.299974 -0.150114)
			(end -0.299974 -0.150114)
			(stroke
				(width 0.1)
				(type default)
			)
			(layer "B.Fab")
		)
		(fp_line
			(start -0.299974 -0.150114)
			(end -0.299974 0.150114)
			(stroke
				(width 0.1)
				(type default)
			)
			(layer "B.Fab")
		)
		(fp_line
			(start 0.299974 0.150114)
			(end 0.299974 -0.150114)
			(stroke
				(width 0.1)
				(type default)
			)
			(layer "B.Fab")
		)
		(fp_line
			(start -0.299974 0.150114)
			(end 0.299974 0.150114)
			(stroke
				(width 0.1)
				(type default)
			)
			(layer "B.Fab")
		)
		(pad "1" smd rect
			(at 0.2667 0 270)
			(size 0.3048 0.381)
			(layers "B.Cu" "B.Mask" "B.Paste")
			(net "P0V9_CPU0_RT2_2A")
		)
		(pad "2" smd rect
			(at -0.2667 0 270)
			(size 0.3048 0.381)
			(layers "B.Cu" "B.Mask" "B.Paste")
			(net "GND")
		)
	)
	(footprint ""
		(layer "B.Cu")
		(at 182.332376 -113.862866 180)
		(property "Reference" "C357"
			(at 0 0 0)
			(layer "B.SilkS")
			(hide yes)
			(effects
				(font
					(size 1.27 1.27)
				)
				(justify mirror)
			)
		)
		(property "Value" ""
			(at 0 0 0)
			(layer "B.Fab")
			(effects
				(font
					(size 1.27 1.27)
				)
				(justify mirror)
			)
		)
		(duplicate_pad_numbers_are_jumpers no)
		(fp_line
			(start 0.69215 0.2921)
			(end 0.69215 -0.2921)
			(stroke
				(width 0.1524)
				(type default)
			)
			(layer "B.SilkS")
		)
		(fp_line
			(start 0.69215 -0.2921)
			(end -0.69215 -0.2921)
			(stroke
				(width 0.1524)
				(type default)
			)
			(layer "B.SilkS")
		)
		(fp_line
			(start -0.69215 0.2921)
			(end 0.69215 0.2921)
			(stroke
				(width 0.1524)
				(type default)
			)
			(layer "B.SilkS")
		)
		(fp_line
			(start -0.69215 -0.2921)
			(end -0.69215 0.2921)
			(stroke
				(width 0.1524)
				(type default)
			)
			(layer "B.SilkS")
		)
		(fp_line
			(start 0.51435 0.2794)
			(end 0.51435 -0.2794)
			(stroke
				(width 0.1)
				(type default)
			)
			(layer "B.Fab")
		)
		(fp_line
			(start 0.51435 -0.2794)
			(end -0.51435 -0.2794)
			(stroke
				(width 0.1)
				(type default)
			)
			(layer "B.Fab")
		)
		(fp_line
			(start -0.51435 0.2794)
			(end 0.51435 0.2794)
			(stroke
				(width 0.1)
				(type default)
			)
			(layer "B.Fab")
		)
		(fp_line
			(start -0.51435 -0.2794)
			(end -0.51435 0.2794)
			(stroke
				(width 0.1)
				(type default)
			)
			(layer "B.Fab")
		)
		(pad "1" smd circle
			(at 0.40005 0)
			(size 0 0)
			(layers "B.Cu" "B.Mask" "B.Paste")
			(net "P3V3_AUX")
		)
		(pad "2" smd circle
			(at -0.40005 0)
			(size 0 0)
			(layers "B.Cu" "B.Mask" "B.Paste")
			(net "GND")
		)
		(zone
			(layer "B.Cu")
			(hatch none 0.5)
			(connect_pads
				(clearance 0)
			)
			(min_thickness 0.25)
			(keepout
				(tracks not_allowed)
				(vias allowed)
				(pads allowed)
				(copperpour not_allowed)
				(footprints allowed)
			)
			(placement
				(enabled no)
				(sheetname "")
			)
			(fill
				(thermal_gap 0.5)
				(thermal_bridge_width 0.5)
				(island_removal_mode 0)
			)
			(polygon
				(pts
					(xy 182.141876 -113.774982) (xy 182.141876 -113.950496) (xy 182.233316 -114.008662) (xy 182.432706 -114.008662)
					(xy 182.522876 -113.950496) (xy 182.522876 -113.775236) (xy 182.432706 -113.716816) (xy 182.233316 -113.716816)
				)
			)
		)
	)
	(footprint ""
		(layer "B.Cu")
		(at 308.363366 -416.899344 90)
		(property "Reference" "C6536"
			(at 0 0 90)
			(layer "B.SilkS")
			(hide yes)
			(effects
				(font
					(size 1.27 1.27)
				)
				(justify mirror)
			)
		)
		(property "Value" ""
			(at 0 0 90)
			(layer "B.Fab")
			(effects
				(font
					(size 1.27 1.27)
				)
				(justify mirror)
			)
		)
		(duplicate_pad_numbers_are_jumpers no)
		(fp_line
			(start 0.299974 -0.150114)
			(end -0.299974 -0.150114)
			(stroke
				(width 0.1)
				(type default)
			)
			(layer "B.Fab")
		)
		(fp_line
			(start -0.299974 -0.150114)
			(end -0.299974 0.150114)
			(stroke
				(width 0.1)
				(type default)
			)
			(layer "B.Fab")
		)
		(fp_line
			(start 0.299974 0.150114)
			(end 0.299974 -0.150114)
			(stroke
				(width 0.1)
				(type default)
			)
			(layer "B.Fab")
		)
		(fp_line
			(start -0.299974 0.150114)
			(end 0.299974 0.150114)
			(stroke
				(width 0.1)
				(type default)
			)
			(layer "B.Fab")
		)
		(pad "1" smd rect
			(at 0.2667 0 270)
			(size 0.3048 0.381)
			(layers "B.Cu" "B.Mask" "B.Paste")
			(net "P5E_CPU0_P1_TX_BUF_C_DN<1>")
		)
		(pad "2" smd rect
			(at -0.2667 0 270)
			(size 0.3048 0.381)
			(layers "B.Cu" "B.Mask" "B.Paste")
			(net "P5E_CPU0_P1_TX_BUF_DN<1>")
		)
	)
	(footprint ""
		(layer "B.Cu")
		(at 376.472958 -208.530952 90)
		(property "Reference" "C210"
			(at 0 0 90)
			(layer "B.SilkS")
			(hide yes)
			(effects
				(font
					(size 1.27 1.27)
				)
				(justify mirror)
			)
		)
		(property "Value" ""
			(at 0 0 90)
			(layer "B.Fab")
			(effects
				(font
					(size 1.27 1.27)
				)
				(justify mirror)
			)
		)
		(duplicate_pad_numbers_are_jumpers no)
		(fp_line
			(start 0.7874 -0.4064)
			(end -0.7874 -0.4064)
			(stroke
				(width 0.1524)
				(type default)
			)
			(layer "B.SilkS")
		)
		(fp_line
			(start -0.7874 -0.4064)
			(end -0.7874 0.4064)
			(stroke
				(width 0.1524)
				(type default)
			)
			(layer "B.SilkS")
		)
		(fp_line
			(start 0.7874 0.4064)
			(end 0.7874 -0.4064)
			(stroke
				(width 0.1524)
				(type default)
			)
			(layer "B.SilkS")
		)
		(fp_line
			(start -0.7874 0.4064)
			(end 0.7874 0.4064)
			(stroke
				(width 0.1524)
				(type default)
			)
			(layer "B.SilkS")
		)
		(fp_line
			(start 0.67945 -0.305054)
			(end 0.12065 -0.305054)
			(stroke
				(width 0.1)
				(type default)
			)
			(layer "B.Fab")
		)
		(fp_line
			(start 0.12065 -0.305054)
			(end 0.12065 -0.2794)
			(stroke
				(width 0.1)
				(type default)
			)
			(layer "B.Fab")
		)
		(fp_line
			(start -0.12065 -0.3048)
			(end -0.67945 -0.3048)
			(stroke
				(width 0.1)
				(type default)
			)
			(layer "B.Fab")
		)
		(fp_line
			(start -0.67945 -0.3048)
			(end -0.67945 0.3048)
			(stroke
				(width 0.1)
				(type default)
			)
			(layer "B.Fab")
		)
		(fp_line
			(start 0.12065 -0.2794)
			(end -0.12065 -0.2794)
			(stroke
				(width 0.1)
				(type default)
			)
			(layer "B.Fab")
		)
		(fp_line
			(start -0.12065 -0.2794)
			(end -0.12065 -0.3048)
			(stroke
				(width 0.1)
				(type default)
			)
			(layer "B.Fab")
		)
		(fp_line
			(start 0.12065 0.2794)
			(end 0.12065 0.3048)
			(stroke
				(width 0.1)
				(type default)
			)
			(layer "B.Fab")
		)
		(fp_line
			(start -0.120396 0.2794)
			(end 0.12065 0.2794)
			(stroke
				(width 0.1)
				(type default)
			)
			(layer "B.Fab")
		)
		(fp_line
			(start 0.67945 0.3048)
			(end 0.67945 -0.305054)
			(stroke
				(width 0.1)
				(type default)
			)
			(layer "B.Fab")
		)
		(fp_line
			(start 0.12065 0.3048)
			(end 0.67945 0.3048)
			(stroke
				(width 0.1)
				(type default)
			)
			(layer "B.Fab")
		)
		(fp_line
			(start -0.120396 0.3048)
			(end -0.120396 0.2794)
			(stroke
				(width 0.1)
				(type default)
			)
			(layer "B.Fab")
		)
		(fp_line
			(start -0.67945 0.3048)
			(end -0.120396 0.3048)
			(stroke
				(width 0.1)
				(type default)
			)
			(layer "B.Fab")
		)
		(pad "1" smd circle
			(at 0.40005 0 270)
			(size 0 0)
			(layers "B.Cu" "B.Mask" "B.Paste")
			(net "JTAG_CPU0_TCK")
		)
		(pad "2" smd circle
			(at -0.40005 0 270)
			(size 0 0)
			(layers "B.Cu" "B.Mask" "B.Paste")
			(net "GND")
		)
	)
)
